# BASEBOARD_FAB2 (Tioga Pass) — schematic netlist excerpt (pin names and nets, part order shuffled) for the footprints in the layout excerpt that follows; sources: Cadence DE-HDL packaged netlist, KiCad conversion of Wiwynn_Tioga_Pass_MB.brd

Q4B2  FET_N_DUAL  NTJD4001N FET  pkg SMLF  page 95
  SOURCE(0)  = GND
  GATE(0)  = FM_SYS_THROTTLE_LVC3
  DRAIN(0)  = H_CPU1_MEMKLM_MEMHOT_G_N
  SOURCE(0)  = GND
  GATE(0)  = FM_SYS_THROTTLE_LVC3
  DRAIN(0)  = H_CPU1_MEMGHJ_MEMHOT_G_N

R4B5  RES  20.0K 1% CHIP  pkg 0402  page 234 : A = VSENSE_PVPP_KLM ; B = VR_FB_PVPP_KLM

(kicad_pcb
	(version 20260206)
	(generator "pcbnew")
	(generator_version "10.0")
	(general
		(thickness 1.6)
		(legacy_teardrops no)
	)
	(paper "A4")
	(title_block
		(title "Wiwynn_Tioga_Pass_MB.brd")
		(comment 1 "Tioga Pass / footprints 2202-2203 of 4770")
	)
	(layers
		(0 "F.Cu" signal "TOP")
		(4 "In1.Cu" signal "L2GND")
		(6 "In2.Cu" signal "L3")
		(8 "In3.Cu" signal "L4GND")
		(10 "In4.Cu" signal "L5")
		(12 "In5.Cu" signal "L6GND")
		(14 "In6.Cu" signal "L7VCC")
		(16 "In7.Cu" signal "L8VCC")
		(18 "In8.Cu" signal "L9GND")
		(20 "In9.Cu" signal "L10")
		(22 "In10.Cu" signal "L11GND")
		(24 "In11.Cu" signal "L12")
		(26 "In12.Cu" signal "L13GND")
		(2 "B.Cu" signal "BOTTOM")
		(9 "F.Adhes" user "F.Adhesive")
		(11 "B.Adhes" user "B.Adhesive")
		(13 "F.Paste" user "Package Geometry/Pastemask Top")
		(15 "B.Paste" user "Package Geometry/Pastemask Bottom")
		(5 "F.SilkS" user "Ref Des/Silkscreen Top")
		(7 "B.SilkS" user "Ref Des/Silkscreen Bottom")
		(1 "F.Mask" user "Board Geometry/Soldermask Top")
		(3 "B.Mask" user "Board Geometry/Soldermask Bottom")
		(17 "Dwgs.User" user "User.Drawings")
		(19 "Cmts.User" user "User.Comments")
		(21 "Eco1.User" user "User.Eco1")
		(23 "Eco2.User" user "User.Eco2")
		(25 "Edge.Cuts" user "Board Geometry/Outline")
		(27 "Margin" user)
		(31 "F.CrtYd" user "Package Geometry/Place Bound Top")
		(29 "B.CrtYd" user "Package Geometry/Place Bound Bottom")
		(35 "F.Fab" user "Ref Des/Assembly Top")
		(33 "B.Fab" user "Ref Des/Assembly Bottom")
	)
	(footprint ""
		(layer "F.Cu")
		(at 163.88842 -124.5235)
		(property "Reference" "Q4B2"
			(at 1.33858 -1.05283 0)
			(unlocked yes)
			(layer "F.SilkS")
			(effects
				(font
					(size 0.7874 0.5842)
					(thickness 0.1524)
				)
				(justify left)
			)
		)
		(property "Value" ""
			(at 0 0 0)
			(layer "F.Fab")
			(effects
				(font
					(size 1.27 1.27)
				)
			)
		)
		(duplicate_pad_numbers_are_jumpers no)
		(fp_circle
			(center -0.508 -0.7874)
			(end -0.381 -0.7874)
			(stroke
				(width 0.254)
				(type default)
			)
			(fill no)
			(layer "F.SilkS")
		)
		(fp_poly
			(pts
				(xy 0.2159 1.7526) (xy 1.5621 1.7526) (xy 1.5621 -0.4572) (xy 0.2159 -0.4572)
			)
			(stroke
				(width 0)
				(type default)
			)
			(fill no)
			(layer "F.CrtYd")
		)
		(fp_line
			(start 0.2159 -0.45466)
			(end 0.2159 1.75514)
			(stroke
				(width 0.1)
				(type default)
			)
			(layer "F.Fab")
		)
		(fp_line
			(start 0.2159 1.75514)
			(end 1.5621 1.75514)
			(stroke
				(width 0.1)
				(type default)
			)
			(layer "F.Fab")
		)
		(fp_line
			(start 1.5621 -0.45466)
			(end 0.2159 -0.45466)
			(stroke
				(width 0.1)
				(type default)
			)
			(layer "F.Fab")
		)
		(fp_line
			(start 1.5621 1.75514)
			(end 1.5621 -0.45466)
			(stroke
				(width 0.1)
				(type default)
			)
			(layer "F.Fab")
		)
		(fp_circle
			(center -0.508 -0.7874)
			(end -0.381 -0.7874)
			(stroke
				(width 0.254)
				(type default)
			)
			(fill no)
			(layer "F.Fab")
		)
		(pad "1" smd rect
			(at 0 0)
			(size 1.016 0.381)
			(layers "F.Cu" "F.Mask" "F.Paste")
			(net "GND")
		)
		(pad "2" smd rect
			(at 0 0.65024)
			(size 1.016 0.381)
			(layers "F.Cu" "F.Mask" "F.Paste")
			(net "FM_SYS_THROTTLE_LVC3")
		)
		(pad "3" smd rect
			(at 0 1.30048)
			(size 1.016 0.381)
			(layers "F.Cu" "F.Mask" "F.Paste")
			(net "H_CPU1_MEMKLM_MEMHOT_G_N")
		)
		(pad "4" smd rect
			(at 1.778 1.30048)
			(size 1.016 0.381)
			(layers "F.Cu" "F.Mask" "F.Paste")
			(net "GND")
		)
		(pad "5" smd rect
			(at 1.778 0.65024)
			(size 1.016 0.381)
			(layers "F.Cu" "F.Mask" "F.Paste")
			(net "FM_SYS_THROTTLE_LVC3")
		)
		(pad "6" smd rect
			(at 1.778 0)
			(size 1.016 0.381)
			(layers "F.Cu" "F.Mask" "F.Paste")
			(net "H_CPU1_MEMGHJ_MEMHOT_G_N")
		)
		(zone
			(layer "F.Cu")
			(hatch none 0.5)
			(connect_pads
				(clearance 0)
			)
			(min_thickness 0.25)
			(keepout
				(tracks allowed)
				(vias not_allowed)
				(pads allowed)
				(copperpour not_allowed)
				(footprints allowed)
			)
			(placement
				(enabled no)
				(sheetname "")
			)
			(fill
				(thermal_gap 0.5)
				(thermal_bridge_width 0.5)
				(island_removal_mode 0)
			)
			(polygon
				(pts
					(xy 163.38042 -124.714) (xy 164.39642 -124.714) (xy 164.39642 -123.0249) (xy 163.38042 -123.0249)
				)
			)
		)
		(zone
			(layer "F.Cu")
			(hatch none 0.5)
			(connect_pads
				(clearance 0)
			)
			(min_thickness 0.25)
			(keepout
				(tracks allowed)
				(vias not_allowed)
				(pads allowed)
				(copperpour not_allowed)
				(footprints allowed)
			)
			(placement
				(enabled no)
				(sheetname "")
			)
			(fill
				(thermal_gap 0.5)
				(thermal_bridge_width 0.5)
				(island_removal_mode 0)
			)
			(polygon
				(pts
					(xy 165.15842 -124.714) (xy 166.17442 -124.714) (xy 166.17442 -123.0249) (xy 165.15842 -123.0249)
				)
			)
		)
	)
	(footprint ""
		(layer "F.Cu")
		(at 170.7896 -131.0005 180)
		(property "Reference" "R4B5"
			(at 0 0 180)
			(layer "F.SilkS")
			(hide yes)
			(effects
				(font
					(size 1.27 1.27)
				)
			)
		)
		(property "Value" ""
			(at 0 0 180)
			(layer "F.Fab")
			(effects
				(font
					(size 1.27 1.27)
				)
			)
		)
		(duplicate_pad_numbers_are_jumpers no)
		(fp_poly
			(pts
				(xy -0.2794 -0.1016) (xy 0.2794 -0.1016) (xy 0.2794 0.9906) (xy -0.2794 0.9906)
			)
			(stroke
				(width 0)
				(type default)
			)
			(fill no)
			(layer "F.CrtYd")
		)
		(fp_line
			(start 0.2794 0.9906)
			(end 0.2794 -0.1016)
			(stroke
				(width 0.1)
				(type default)
			)
			(layer "F.Fab")
		)
		(fp_line
			(start 0.2794 -0.1016)
			(end -0.2794 -0.1016)
			(stroke
				(width 0.1)
				(type default)
			)
			(layer "F.Fab")
		)
		(fp_line
			(start -0.2794 0.9906)
			(end 0.2794 0.9906)
			(stroke
				(width 0.1)
				(type default)
			)
			(layer "F.Fab")
		)
		(fp_line
			(start -0.2794 -0.1016)
			(end -0.2794 0.9906)
			(stroke
				(width 0.1)
				(type default)
			)
			(layer "F.Fab")
		)
		(pad "1" smd rect
			(at 0 0 180)
			(size 0.508 0.508)
			(layers "F.Cu" "F.Mask" "F.Paste")
			(net "VSENSE_PVPP_KLM")
		)
		(pad "2" smd rect
			(at 0 0.889 180)
			(size 0.508 0.508)
			(layers "F.Cu" "F.Mask" "F.Paste")
			(net "VR_FB_PVPP_KLM")
		)
		(zone
			(layer "F.Cu")
			(hatch none 0.5)
			(connect_pads
				(clearance 0)
			)
			(min_thickness 0.25)
			(keepout
				(tracks not_allowed)
				(vias allowed)
				(pads allowed)
				(copperpour not_allowed)
				(footprints allowed)
			)
			(placement
				(enabled no)
				(sheetname "")
			)
			(fill
				(thermal_gap 0.5)
				(thermal_bridge_width 0.5)
				(island_removal_mode 0)
			)
			(polygon
				(pts
					(xy 171.0436 -131.6355) (xy 170.5356 -131.6355) (xy 170.5356 -131.2545) (xy 171.0436 -131.2545)
				)
			)
		)
		(zone
			(layer "F.Cu")
			(hatch none 0.5)
			(connect_pads
				(clearance 0)
			)
			(min_thickness 0.25)
			(keepout
				(tracks allowed)
				(vias not_allowed)
				(pads allowed)
				(copperpour not_allowed)
				(footprints allowed)
			)
			(placement
				(enabled no)
				(sheetname "")
			)
			(fill
				(thermal_gap 0.5)
				(thermal_bridge_width 0.5)
				(island_removal_mode 0)
			)
			(polygon
				(pts
					(xy 171.0436 -131.2545) (xy 170.5356 -131.2545) (xy 170.5356 -131.6355) (xy 171.0436 -131.6355)
				)
			)
		)
	)
)
